(kicad_pcb
	(version 20241229)
	(generator "pcbnew")
	(generator_version "9.0")
	(general
		(thickness 1.599998)
		(legacy_teardrops no)
	)
	(paper "A4")
	(title_block
		(date "2023-02-12")
		(rev "1.1.5")
		(comment 9 "footprints 392-396 of 473")
	)
	(layers
		(0 "F.Cu" signal)
		(4 "In1.Cu" power "In1.GND")
		(6 "In2.Cu" signal)
		(8 "In3.Cu" power "In3.GND")
		(10 "In4.Cu" power "In4.VCC")
		(12 "In5.Cu" signal)
		(14 "In6.Cu" power "In6.VCC")
		(2 "B.Cu" signal)
		(9 "F.Adhes" user "F.Adhesive")
		(11 "B.Adhes" user "B.Adhesive")
		(13 "F.Paste" user)
		(15 "B.Paste" user)
		(5 "F.SilkS" user "F.Silkscreen")
		(7 "B.SilkS" user "B.Silkscreen")
		(1 "F.Mask" user)
		(3 "B.Mask" user)
		(17 "Dwgs.User" user "User.Drawings")
		(19 "Cmts.User" user "User.Comments")
		(21 "Eco1.User" user "User.Eco1")
		(23 "Eco2.User" user "User.Eco2")
		(25 "Edge.Cuts" user)
		(27 "Margin" user)
		(31 "F.CrtYd" user "F.Courtyard")
		(29 "B.CrtYd" user "B.Courtyard")
		(35 "F.Fab" user)
		(33 "B.Fab" user)
	)
	(footprint "antmicro-footprints:C_0201"
		(layer "B.Cu")
		(at 160.036328 91.497157)
		(descr "Capacitor SMD 0201")
		(tags "capacitor SMD 0201")
		(property "Reference" "C51"
			(at -0.536328 0.402843 180)
			(layer "B.SilkS")
			(effects
				(font
					(size 0.7 0.7)
					(thickness 0.15)
				)
				(justify left bottom mirror)
			)
		)
		(property "Value" "C_100n_0201"
			(at 0 -1.4 180)
			(layer "B.Fab")
			(effects
				(font
					(size 0.7 0.7)
					(thickness 0.15)
				)
				(justify left bottom mirror)
			)
		)
		(property "Description" " "
			(at 0 0 0)
			(layer "F.Fab")
			(hide yes)
			(effects
				(font
					(size 1.27 1.27)
					(thickness 0.15)
				)
			)
		)
		(property "Author" "Antmicro"
			(at 0 0 0)
			(layer "B.Fab")
			(hide yes)
			(effects
				(font
					(size 1 1)
					(thickness 0.15)
				)
				(justify mirror)
			)
		)
		(property "Dielectric" ""
			(at 0 0 0)
			(layer "B.Fab")
			(hide yes)
			(effects
				(font
					(size 1 1)
					(thickness 0.15)
				)
				(justify mirror)
			)
		)
		(property "License" "Apache-2.0"
			(at 0 0 0)
			(layer "B.Fab")
			(hide yes)
			(effects
				(font
					(size 1 1)
					(thickness 0.15)
				)
				(justify mirror)
			)
		)
		(property "MPN" "CC0201KRX6S5BB104"
			(at 0 0 0)
			(layer "B.Fab")
			(hide yes)
			(effects
				(font
					(size 1 1)
					(thickness 0.15)
				)
				(justify mirror)
			)
		)
		(property "Manufacturer" "Yaego"
			(at 0 0 0)
			(layer "B.Fab")
			(hide yes)
			(effects
				(font
					(size 1 1)
					(thickness 0.15)
				)
				(justify mirror)
			)
		)
		(property "Val" "100n"
			(at 0 0 0)
			(layer "B.Fab")
			(hide yes)
			(effects
				(font
					(size 1 1)
					(thickness 0.15)
				)
				(justify mirror)
			)
		)
		(property "Voltage" ""
			(at 0 0 0)
			(layer "B.Fab")
			(hide yes)
			(effects
				(font
					(size 1 1)
					(thickness 0.15)
				)
				(justify mirror)
			)
		)
		(sheetname "FPGA power")
		(sheetfile "fpga-power.kicad_sch")
		(attr smd)
		(fp_rect
			(start -0.72 0.38)
			(end 0.72 -0.38)
			(stroke
				(width 0.05)
				(type solid)
			)
			(fill no)
			(layer "B.CrtYd")
		)
		(fp_rect
			(start 0.3 -0.15)
			(end -0.301 0.149)
			(stroke
				(width 0.15)
				(type solid)
			)
			(fill no)
			(layer "B.Fab")
		)
		(pad "" smd roundrect
			(at -0.349 0.002)
			(size 0.318 0.36)
			(layers "B.Paste")
			(roundrect_rratio 0.25)
		)
		(pad "" smd roundrect
			(at 0.341 0.002)
			(size 0.318 0.36)
			(layers "B.Paste")
			(roundrect_rratio 0.25)
		)
		(pad "1" smd roundrect
			(at -0.321 0.002)
			(size 0.46 0.4)
			(layers "B.Cu" "B.Mask")
			(roundrect_rratio 0.25)
			(net 66 "VDDQ")
			(pintype "passive")
		)
		(pad "2" smd roundrect
			(at 0.32 0.002)
			(size 0.46 0.4)
			(layers "B.Cu" "B.Mask")
			(roundrect_rratio 0.25)
			(net 5 "GND")
			(pintype "passive")
		)
	)
	(footprint "antmicro-footprints:C_0201"
		(layer "B.Cu")
		(at 171.511328 95.622157 180)
		(descr "Capacitor SMD 0201")
		(tags "capacitor SMD 0201")
		(property "Reference" "C29"
			(at -1.088672 0.322157 0)
			(layer "B.SilkS")
			(effects
				(font
					(size 0.7 0.7)
					(thickness 0.15)
				)
				(justify left bottom mirror)
			)
		)
		(property "Value" "C_100n_0201"
			(at 0 -1.4 0)
			(layer "B.Fab")
			(effects
				(font
					(size 0.7 0.7)
					(thickness 0.15)
				)
				(justify left bottom mirror)
			)
		)
		(property "Description" " "
			(at 0 0 180)
			(layer "F.Fab")
			(hide yes)
			(effects
				(font
					(size 1.27 1.27)
					(thickness 0.15)
				)
			)
		)
		(property "Author" "Antmicro"
			(at 343.022656 191.244314 0)
			(layer "B.Fab")
			(hide yes)
			(effects
				(font
					(size 1 1)
					(thickness 0.15)
				)
				(justify mirror)
			)
		)
		(property "Dielectric" ""
			(at 343.022656 191.244314 0)
			(layer "B.Fab")
			(hide yes)
			(effects
				(font
					(size 1 1)
					(thickness 0.15)
				)
				(justify mirror)
			)
		)
		(property "License" "Apache-2.0"
			(at 343.022656 191.244314 0)
			(layer "B.Fab")
			(hide yes)
			(effects
				(font
					(size 1 1)
					(thickness 0.15)
				)
				(justify mirror)
			)
		)
		(property "MPN" "CC0201KRX6S5BB104"
			(at 343.022656 191.244314 0)
			(layer "B.Fab")
			(hide yes)
			(effects
				(font
					(size 1 1)
					(thickness 0.15)
				)
				(justify mirror)
			)
		)
		(property "Manufacturer" "Yaego"
			(at 343.022656 191.244314 0)
			(layer "B.Fab")
			(hide yes)
			(effects
				(font
					(size 1 1)
					(thickness 0.15)
				)
				(justify mirror)
			)
		)
		(property "Val" "100n"
			(at 343.022656 191.244314 0)
			(layer "B.Fab")
			(hide yes)
			(effects
				(font
					(size 1 1)
					(thickness 0.15)
				)
				(justify mirror)
			)
		)
		(property "Voltage" ""
			(at 343.022656 191.244314 0)
			(layer "B.Fab")
			(hide yes)
			(effects
				(font
					(size 1 1)
					(thickness 0.15)
				)
				(justify mirror)
			)
		)
		(sheetname "FPGA power")
		(sheetfile "fpga-power.kicad_sch")
		(attr smd)
		(fp_rect
			(start -0.72 0.38)
			(end 0.72 -0.38)
			(stroke
				(width 0.05)
				(type solid)
			)
			(fill no)
			(layer "B.CrtYd")
		)
		(fp_rect
			(start 0.3 -0.15)
			(end -0.301 0.149)
			(stroke
				(width 0.15)
				(type solid)
			)
			(fill no)
			(layer "B.Fab")
		)
		(pad "" smd roundrect
			(at -0.349 0.002 180)
			(size 0.318 0.36)
			(layers "B.Paste")
			(roundrect_rratio 0.25)
		)
		(pad "" smd roundrect
			(at 0.341 0.002 180)
			(size 0.318 0.36)
			(layers "B.Paste")
			(roundrect_rratio 0.25)
		)
		(pad "1" smd roundrect
			(at -0.321 0.002 180)
			(size 0.46 0.4)
			(layers "B.Cu" "B.Mask")
			(roundrect_rratio 0.25)
			(net 465 "1V0_SYS")
			(pintype "passive")
		)
		(pad "2" smd roundrect
			(at 0.32 0.002 180)
			(size 0.46 0.4)
			(layers "B.Cu" "B.Mask")
			(roundrect_rratio 0.25)
			(net 5 "GND")
			(pintype "passive")
		)
	)
	(footprint "antmicro-footprints:C_0402_1005Metric"
		(layer "B.Cu")
		(at 173.25 95.75)
		(descr "Capacitor SMD 0402")
		(tags "capacitor SMD 0402")
		(property "Reference" "C83"
			(at 1.35 -0.45 180)
			(layer "B.SilkS")
			(effects
				(font
					(size 0.7 0.7)
					(thickness 0.15)
				)
				(justify left bottom mirror)
			)
		)
		(property "Value" "C_4u7_0402"
			(at 0 -1.4 180)
			(layer "B.Fab")
			(effects
				(font
					(size 0.7 0.7)
					(thickness 0.15)
				)
				(justify left bottom mirror)
			)
		)
		(property "Description" " "
			(at 0 0 0)
			(layer "F.Fab")
			(hide yes)
			(effects
				(font
					(size 1.27 1.27)
					(thickness 0.15)
				)
			)
		)
		(property "Author" "Antmicro"
			(at 0 0 0)
			(layer "B.Fab")
			(hide yes)
			(effects
				(font
					(size 1 1)
					(thickness 0.15)
				)
				(justify mirror)
			)
		)
		(property "Dielectric" ""
			(at 0 0 0)
			(layer "B.Fab")
			(hide yes)
			(effects
				(font
					(size 1 1)
					(thickness 0.15)
				)
				(justify mirror)
			)
		)
		(property "License" "Apache-2.0"
			(at 0 0 0)
			(layer "B.Fab")
			(hide yes)
			(effects
				(font
					(size 1 1)
					(thickness 0.15)
				)
				(justify mirror)
			)
		)
		(property "MPN" "GRM155R61A475MEAAD"
			(at 0 0 0)
			(layer "B.Fab")
			(hide yes)
			(effects
				(font
					(size 1 1)
					(thickness 0.15)
				)
				(justify mirror)
			)
		)
		(property "Manufacturer" "Murata"
			(at 0 0 0)
			(layer "B.Fab")
			(hide yes)
			(effects
				(font
					(size 1 1)
					(thickness 0.15)
				)
				(justify mirror)
			)
		)
		(property "Val" "4u7"
			(at 0 0 0)
			(layer "B.Fab")
			(hide yes)
			(effects
				(font
					(size 1 1)
					(thickness 0.15)
				)
				(justify mirror)
			)
		)
		(property "Voltage" ""
			(at 0 0 0)
			(layer "B.Fab")
			(hide yes)
			(effects
				(font
					(size 1 1)
					(thickness 0.15)
				)
				(justify mirror)
			)
		)
		(sheetname "FPGA power")
		(sheetfile "fpga-power.kicad_sch")
		(attr smd)
		(fp_rect
			(start -0.94 0.47)
			(end 0.94 -0.47)
			(stroke
				(width 0.05)
				(type solid)
			)
			(fill no)
			(layer "B.CrtYd")
		)
		(fp_rect
			(start -0.499 0.249)
			(end 0.499 -0.249)
			(stroke
				(width 0.15)
				(type solid)
			)
			(fill no)
			(layer "B.Fab")
		)
		(pad "1" smd roundrect
			(at -0.484 0)
			(size 0.59 0.64)
			(layers "B.Cu" "B.Mask" "B.Paste")
			(roundrect_rratio 0.25)
			(net 465 "1V0_SYS")
			(pintype "passive")
		)
		(pad "2" smd roundrect
			(at 0.484 0)
			(size 0.59 0.64)
			(layers "B.Cu" "B.Mask" "B.Paste")
			(roundrect_rratio 0.25)
			(net 5 "GND")
			(pintype "passive")
		)
	)
	(footprint "antmicro-footprints:C_0201"
		(layer "B.Cu")
		(at 172.736328 99.497157 90)
		(descr "Capacitor SMD 0201")
		(tags "capacitor SMD 0201")
		(property "Reference" "C37"
			(at 1.097157 -0.336328 270)
			(layer "B.SilkS")
			(effects
				(font
					(size 0.7 0.7)
					(thickness 0.15)
				)
				(justify left bottom mirror)
			)
		)
		(property "Value" "C_100n_0201"
			(at 0 -1.4 270)
			(layer "B.Fab")
			(effects
				(font
					(size 0.7 0.7)
					(thickness 0.15)
				)
				(justify left bottom mirror)
			)
		)
		(property "Description" " "
			(at 0 0 90)
			(layer "F.Fab")
			(hide yes)
			(effects
				(font
					(size 1.27 1.27)
					(thickness 0.15)
				)
			)
		)
		(property "Author" "Antmicro"
			(at 272.233485 -73.239171 0)
			(layer "B.Fab")
			(hide yes)
			(effects
				(font
					(size 1 1)
					(thickness 0.15)
				)
				(justify mirror)
			)
		)
		(property "Dielectric" ""
			(at 272.233485 -73.239171 0)
			(layer "B.Fab")
			(hide yes)
			(effects
				(font
					(size 1 1)
					(thickness 0.15)
				)
				(justify mirror)
			)
		)
		(property "License" "Apache-2.0"
			(at 272.233485 -73.239171 0)
			(layer "B.Fab")
			(hide yes)
			(effects
				(font
					(size 1 1)
					(thickness 0.15)
				)
				(justify mirror)
			)
		)
		(property "MPN" "CC0201KRX6S5BB104"
			(at 272.233485 -73.239171 0)
			(layer "B.Fab")
			(hide yes)
			(effects
				(font
					(size 1 1)
					(thickness 0.15)
				)
				(justify mirror)
			)
		)
		(property "Manufacturer" "Yaego"
			(at 272.233485 -73.239171 0)
			(layer "B.Fab")
			(hide yes)
			(effects
				(font
					(size 1 1)
					(thickness 0.15)
				)
				(justify mirror)
			)
		)
		(property "Val" "100n"
			(at 272.233485 -73.239171 0)
			(layer "B.Fab")
			(hide yes)
			(effects
				(font
					(size 1 1)
					(thickness 0.15)
				)
				(justify mirror)
			)
		)
		(property "Voltage" ""
			(at 272.233485 -73.239171 0)
			(layer "B.Fab")
			(hide yes)
			(effects
				(font
					(size 1 1)
					(thickness 0.15)
				)
				(justify mirror)
			)
		)
		(sheetname "FPGA power")
		(sheetfile "fpga-power.kicad_sch")
		(attr smd)
		(fp_rect
			(start -0.72 0.38)
			(end 0.72 -0.38)
			(stroke
				(width 0.05)
				(type solid)
			)
			(fill no)
			(layer "B.CrtYd")
		)
		(fp_rect
			(start 0.3 -0.15)
			(end -0.301 0.149)
			(stroke
				(width 0.15)
				(type solid)
			)
			(fill no)
			(layer "B.Fab")
		)
		(pad "" smd roundrect
			(at -0.349 0.002 90)
			(size 0.318 0.36)
			(layers "B.Paste")
			(roundrect_rratio 0.25)
		)
		(pad "" smd roundrect
			(at 0.341 0.002 90)
			(size 0.318 0.36)
			(layers "B.Paste")
			(roundrect_rratio 0.25)
		)
		(pad "1" smd roundrect
			(at -0.321 0.002 90)
			(size 0.46 0.4)
			(layers "B.Cu" "B.Mask")
			(roundrect_rratio 0.25)
			(net 465 "1V0_SYS")
			(pintype "passive")
		)
		(pad "2" smd roundrect
			(at 0.32 0.002 90)
			(size 0.46 0.4)
			(layers "B.Cu" "B.Mask")
			(roundrect_rratio 0.25)
			(net 5 "GND")
			(pintype "passive")
		)
	)
	(footprint "antmicro-footprints:C_0402_1005Metric"
		(layer "B.Cu")
		(at 167.75 90.497157 90)
		(descr "Capacitor SMD 0402")
		(tags "capacitor SMD 0402")
		(property "Reference" "C24"
			(at 2.997157 0.15 270)
			(layer "B.SilkS")
			(effects
				(font
					(size 0.7 0.7)
					(thickness 0.15)
				)
				(justify left bottom mirror)
			)
		)
		(property "Value" "C_470n_0402"
			(at 0 -1.4 270)
			(layer "B.Fab")
			(effects
				(font
					(size 0.7 0.7)
					(thickness 0.15)
				)
				(justify left bottom mirror)
			)
		)
		(property "Description" " "
			(at 0 0 90)
			(layer "F.Fab")
			(hide yes)
			(effects
				(font
					(size 1.27 1.27)
					(thickness 0.15)
				)
			)
		)
		(property "Author" "Antmicro"
			(at 258.247157 -77.252843 0)
			(layer "B.Fab")
			(hide yes)
			(effects
				(font
					(size 1 1)
					(thickness 0.15)
				)
				(justify mirror)
			)
		)
		(property "Dielectric" ""
			(at 258.247157 -77.252843 0)
			(layer "B.Fab")
			(hide yes)
			(effects
				(font
					(size 1 1)
					(thickness 0.15)
				)
				(justify mirror)
			)
		)
		(property "License" "Apache-2.0"
			(at 258.247157 -77.252843 0)
			(layer "B.Fab")
			(hide yes)
			(effects
				(font
					(size 1 1)
					(thickness 0.15)
				)
				(justify mirror)
			)
		)
		(property "MPN" "C1005X5R1E474M050BB"
			(at 258.247157 -77.252843 0)
			(layer "B.Fab")
			(hide yes)
			(effects
				(font
					(size 1 1)
					(thickness 0.15)
				)
				(justify mirror)
			)
		)
		(property "Manufacturer" "TDK"
			(at 258.247157 -77.252843 0)
			(layer "B.Fab")
			(hide yes)
			(effects
				(font
					(size 1 1)
					(thickness 0.15)
				)
				(justify mirror)
			)
		)
		(property "Val" "470n"
			(at 258.247157 -77.252843 0)
			(layer "B.Fab")
			(hide yes)
			(effects
				(font
					(size 1 1)
					(thickness 0.15)
				)
				(justify mirror)
			)
		)
		(property "Voltage" ""
			(at 258.247157 -77.252843 0)
			(layer "B.Fab")
			(hide yes)
			(effects
				(font
					(size 1 1)
					(thickness 0.15)
				)
				(justify mirror)
			)
		)
		(sheetname "FPGA power")
		(sheetfile "fpga-power.kicad_sch")
		(attr smd)
		(fp_rect
			(start -0.94 0.47)
			(end 0.94 -0.47)
			(stroke
				(width 0.05)
				(type solid)
			)
			(fill no)
			(layer "B.CrtYd")
		)
		(fp_rect
			(start -0.499 0.249)
			(end 0.499 -0.249)
			(stroke
				(width 0.15)
				(type solid)
			)
			(fill no)
			(layer "B.Fab")
		)
		(pad "1" smd roundrect
			(at -0.484 0 90)
			(size 0.59 0.64)
			(layers "B.Cu" "B.Mask" "B.Paste")
			(roundrect_rratio 0.25)
			(net 459 "3V3_SYS")
			(pintype "passive")
		)
		(pad "2" smd roundrect
			(at 0.484 0 90)
			(size 0.59 0.64)
			(layers "B.Cu" "B.Mask" "B.Paste")
			(roundrect_rratio 0.25)
			(net 5 "GND")
			(pintype "passive")
		)
	)
)
